FILE_TYPE = CONNECTIVITY;
{Allegro Design Entry HDL 17.4-2019 S026 (4007227) 1/17/2022}
"PAGE_NUMBER" = 98;
0"NC";
1"GND\g";
2"GND\g";
3"P3V3\g";
4"M_B_CPU1_SA_CB<7:0>";
5"M_B_CPU1_SB_CB<7:0>";
6"M_B_CPU1_SB_CA<6:0>";
7"M_B_CPU1_SA_CA<6:0>";
8"M_B_CPU1_SA_DQ<31:0>";
9"M_B_CPU1_SB_DQ<31:0>";
10"M_B_CPU1_SA_DQS_DN<9:0>";
11"M_B_CPU1_SA_DQS_DP<9:0>";
12"M_B_CPU1_SB_DQS_DP<9:0>";
13"M_B_CPU1_SB_DQS_DN<9:0>";
14"P3V3_AUX\g";
15"PWRGD_CHB_CPU1_DIMM";
16"I3C_SPD_DDRB_CPU1_SDA";
17"I3C_SPD_DDRAF_CPU1_SCL";
18"I3C_SPD_DDRAF_CPU1_SDA";
19"PD_CHB_CPU1_DIMM_SAA";
20"I3C_SPD_DDRB_CPU1_SCL";
21"M_B_CPU1_SB_RSP<0>";
22"M_B_CPU1_SB_DQ<27>";
23"GND\g";
24"GND\g";
25"GND\g";
26"P12V_MEM_CPU1\g";
27"M_B_CPU1_ALERT_N";
28"M_B_CPU1_RESET_N";
29"M_B_CPU1_SB_CB<2>";
30"M_B_CPU1_SB_CB<1>";
31"M_B_CPU1_SB_DQ<22>";
32"PWRGD_CHAF_CPU1";
33"M_B_CPU1_SB_DQ<2>";
34"M_B_CPU1_SA_CA<0>";
35"M_B_CPU1_SA_DQS_DP<7>";
36"M_B_CPU1_SA_DQS_DN<8>";
37"M_B_CPU1_SA_DQ<28>";
38"M_B_CPU1_SA_DQ<19>";
39"M_B_CPU1_SA_DQS_DP<9>";
40"M_B_CPU1_SB_DQS_DP<9>";
41"M_B_CPU1_SB_DQS_DN<9>";
42"M_B_CPU1_SA_DQS_DN<9>";
43"M_B_CPU1_SA_DQS_DP<8>";
44"M_B_CPU1_SB_DQS_DN<7>";
45"M_B_CPU1_SB_DQS_DP<6>";
46"M_B_CPU1_SB_DQS_DN<6>";
47"M_B_CPU1_SA_DQS_DN<6>";
48"M_B_CPU1_SB_DQS_DP<5>";
49"M_B_CPU1_SB_DQS_DN<5>";
50"M_B_CPU1_SA_DQS_DP<5>";
51"M_B_CPU1_SA_DQS_DN<5>";
52"M_B_CPU1_SB_DQS_DP<4>";
53"M_B_CPU1_SB_DQS_DN<4>";
54"M_B_CPU1_SA_DQS_DP<4>";
55"M_B_CPU1_SA_DQS_DN<4>";
56"M_B_CPU1_SB_DQS_DP<3>";
57"M_B_CPU1_SB_DQS_DN<3>";
58"M_B_CPU1_SA_DQS_DP<3>";
59"M_B_CPU1_SA_DQS_DN<3>";
60"M_B_CPU1_SB_DQS_DP<2>";
61"M_B_CPU1_SB_DQS_DN<2>";
62"M_B_CPU1_SA_DQS_DP<2>";
63"M_B_CPU1_SA_DQS_DN<2>";
64"M_B_CPU1_SB_DQS_DP<1>";
65"M_B_CPU1_SB_DQS_DN<1>";
66"M_B_CPU1_SA_DQS_DP<1>";
67"M_B_CPU1_SA_DQS_DN<1>";
68"M_B_CPU1_SB_DQS_DP<0>";
69"M_B_CPU1_SB_DQS_DN<0>";
70"M_B_CPU1_SA_DQS_DP<0>";
71"M_B_CPU1_SA_DQS_DN<0>";
72"M_B_CPU1_SB_DQS_DP<7>";
73"M_B_CPU1_SB_DQS_DN<8>";
74"M_B_CPU1_SB_DQS_DP<8>";
75"M_B_CPU1_SA_DQS_DP<6>";
76"M_B_CPU1_SA_DQS_DN<7>";
77"M_B_CPU1_SA_CA<1>";
78"M_B_CPU1_SA_CA<4>";
79"M_B_CPU1_SA_DQ<31>";
80"M_B_CPU1_SA_DQ<29>";
81"M_B_CPU1_SA_DQ<24>";
82"M_B_CPU1_SB_PAR";
83"M_B_CPU1_SA_PAR";
84"M_B_CPU1_SA_RSP<0>";
85"M_B_CPU1_SB_DQ<0>";
86"M_B_CPU1_SB_DQ<1>";
87"M_B_CPU1_SB_DQ<3>";
88"M_B_CPU1_SB_DQ<4>";
89"M_B_CPU1_SB_DQ<5>";
90"M_B_CPU1_SB_DQ<6>";
91"M_B_CPU1_SB_DQ<7>";
92"M_B_CPU1_SB_DQ<8>";
93"M_B_CPU1_SB_DQ<9>";
94"M_B_CPU1_SB_DQ<10>";
95"M_B_CPU1_SB_DQ<11>";
96"M_B_CPU1_SB_DQ<12>";
97"M_B_CPU1_SB_DQ<13>";
98"M_B_CPU1_SB_DQ<14>";
99"M_B_CPU1_SB_DQ<15>";
100"M_B_CPU1_SB_DQ<16>";
101"M_B_CPU1_SB_DQ<17>";
102"M_B_CPU1_SB_DQ<18>";
103"M_B_CPU1_SB_DQ<19>";
104"M_B_CPU1_SB_DQ<20>";
105"M_B_CPU1_SB_DQ<21>";
106"M_B_CPU1_SB_DQ<23>";
107"M_B_CPU1_SB_DQ<24>";
108"M_B_CPU1_SB_DQ<25>";
109"M_B_CPU1_SB_DQ<26>";
110"M_B_CPU1_SB_DQ<28>";
111"M_B_CPU1_SB_DQ<29>";
112"M_B_CPU1_SB_DQ<30>";
113"M_B_CPU1_SB_DQ<31>";
114"M_B_CPU1_SA_DQ<0>";
115"M_B_CPU1_SA_DQ<1>";
116"M_B_CPU1_SA_DQ<2>";
117"M_B_CPU1_SA_DQ<3>";
118"M_B_CPU1_SA_DQ<4>";
119"M_B_CPU1_SA_DQ<5>";
120"M_B_CPU1_SA_DQ<6>";
121"M_B_CPU1_SA_DQ<7>";
122"M_B_CPU1_SA_DQ<8>";
123"M_B_CPU1_SA_DQ<9>";
124"M_B_CPU1_SA_DQ<10>";
125"M_B_CPU1_SA_DQ<11>";
126"M_B_CPU1_SA_DQ<12>";
127"M_B_CPU1_SA_DQ<13>";
128"M_B_CPU1_SA_DQ<14>";
129"M_B_CPU1_SA_DQ<15>";
130"M_B_CPU1_SA_DQ<16>";
131"M_B_CPU1_SA_DQ<17>";
132"M_B_CPU1_SA_DQ<18>";
133"M_B_CPU1_SA_DQ<20>";
134"M_B_CPU1_SA_DQ<21>";
135"M_B_CPU1_SA_DQ<22>";
136"M_B_CPU1_SA_DQ<23>";
137"M_B_CPU1_SA_DQ<25>";
138"M_B_CPU1_SA_DQ<26>";
139"M_B_CPU1_SA_DQ<27>";
140"M_B_CPU1_SA_DQ<30>";
141"M_B_CPU1_SB_CS_N<1>";
142"M_B_CPU1_SA_CS_N<1>";
143"M_B_CPU1_SB_CS_N<0>";
144"M_B_CPU1_SA_CS_N<0>";
145"M_B_CPU1_CLK_DP<0>";
146"M_B_CPU1_CLK_DN<0>";
147"M_B_CPU1_SB_CB<0>";
148"M_B_CPU1_SB_CB<3>";
149"M_B_CPU1_SB_CB<4>";
150"M_B_CPU1_SB_CB<5>";
151"M_B_CPU1_SB_CB<6>";
152"M_B_CPU1_SA_CB<0>";
153"M_B_CPU1_SA_CB<2>";
154"M_B_CPU1_SA_CB<3>";
155"M_B_CPU1_SA_CB<5>";
156"M_B_CPU1_SA_CB<6>";
157"M_B_CPU1_SB_CA<6>";
158"M_B_CPU1_SA_CA<6>";
159"M_B_CPU1_SB_CA<5>";
160"M_B_CPU1_SA_CA<5>";
161"M_B_CPU1_SB_CA<4>";
162"M_B_CPU1_SB_CA<3>";
163"M_B_CPU1_SA_CA<3>";
164"M_B_CPU1_SB_CA<2>";
165"M_B_CPU1_SA_CA<2>";
166"M_B_CPU1_SB_CA<1>";
167"M_B_CPU1_SB_CA<0>";
168"M_B_CPU1_SB_CB<7>";
169"M_B_CPU1_SA_CB<1>";
170"M_B_CPU1_SA_CB<4>";
171"M_B_CPU1_SA_CB<7>";
172"PD_CHB_CPU1_DIMM_SAA";
%"TAP"
"1","(-6075,4325)","0","mstr_standard","I100";
;
CDS_LIB"mstr_standard"
BODY_TYPE"PLUMBING"
HDL_TAP"TRUE";
"B \NAC \NWC"8;
"S \NAC"
BN"7"121;
%"TAP"
"1","(-6075,4575)","0","mstr_standard","I101";
;
CDS_LIB"mstr_standard"
BODY_TYPE"PLUMBING"
HDL_TAP"TRUE";
"B \NAC \NWC"8;
"S \NAC"
BN"12"126;
%"TAP"
"1","(-6075,4525)","0","mstr_standard","I102";
;
CDS_LIB"mstr_standard"
BODY_TYPE"PLUMBING"
HDL_TAP"TRUE";
"B \NAC \NWC"8;
"S \NAC"
BN"11"125;
%"TAP"
"1","(-6075,4475)","0","mstr_standard","I103";
;
CDS_LIB"mstr_standard"
BODY_TYPE"PLUMBING"
HDL_TAP"TRUE";
"B \NAC \NWC"8;
"S \NAC"
BN"10"124;
%"TAP"
"1","(-6075,4425)","0","mstr_standard","I104";
;
CDS_LIB"mstr_standard"
BODY_TYPE"PLUMBING"
HDL_TAP"TRUE";
"B \NAC \NWC"8;
"S \NAC"
BN"9"123;
%"TAP"
"1","(-6075,4375)","0","mstr_standard","I105";
;
CDS_LIB"mstr_standard"
BODY_TYPE"PLUMBING"
HDL_TAP"TRUE";
"B \NAC \NWC"8;
"S \NAC"
BN"8"122;
%"TAP"
"1","(-6075,4825)","0","mstr_standard","I106";
;
CDS_LIB"mstr_standard"
BODY_TYPE"PLUMBING"
HDL_TAP"TRUE";
"B \NAC \NWC"8;
"S \NAC"
BN"17"131;
%"TAP"
"1","(-6075,4775)","0","mstr_standard","I107";
;
CDS_LIB"mstr_standard"
BODY_TYPE"PLUMBING"
HDL_TAP"TRUE";
"B \NAC \NWC"8;
"S \NAC"
BN"16"130;
%"TAP"
"1","(-6075,4625)","0","mstr_standard","I108";
;
CDS_LIB"mstr_standard"
BODY_TYPE"PLUMBING"
HDL_TAP"TRUE";
"B \NAC \NWC"8;
"S \NAC"
BN"13"127;
%"TAP"
"1","(-6075,4725)","0","mstr_standard","I109";
;
CDS_LIB"mstr_standard"
BODY_TYPE"PLUMBING"
HDL_TAP"TRUE";
"B \NAC \NWC"8;
"S \NAC"
BN"15"129;
%"TAP"
"1","(-6075,4675)","0","mstr_standard","I110";
;
CDS_LIB"mstr_standard"
BODY_TYPE"PLUMBING"
HDL_TAP"TRUE";
"B \NAC \NWC"8;
"S \NAC"
BN"14"128;
%"TAP"
"1","(-6075,5025)","0","mstr_standard","I111";
;
CDS_LIB"mstr_standard"
BODY_TYPE"PLUMBING"
HDL_TAP"TRUE";
"B \NAC \NWC"8;
"S \NAC"
BN"21"134;
%"TAP"
"1","(-6075,5075)","0","mstr_standard","I112";
;
CDS_LIB"mstr_standard"
BODY_TYPE"PLUMBING"
HDL_TAP"TRUE";
"B \NAC \NWC"8;
"S \NAC"
BN"22"135;
%"TAP"
"1","(-6075,4925)","0","mstr_standard","I113";
;
CDS_LIB"mstr_standard"
BODY_TYPE"PLUMBING"
HDL_TAP"TRUE";
"B \NAC \NWC"8;
"S \NAC"
BN"19"38;
%"TAP"
"1","(-6075,4975)","0","mstr_standard","I114";
;
CDS_LIB"mstr_standard"
BODY_TYPE"PLUMBING"
HDL_TAP"TRUE";
"B \NAC \NWC"8;
"S \NAC"
BN"20"133;
%"TAP"
"1","(-6075,4875)","0","mstr_standard","I115";
;
CDS_LIB"mstr_standard"
BODY_TYPE"PLUMBING"
HDL_TAP"TRUE";
"B \NAC \NWC"8;
"S \NAC"
BN"18"132;
%"TAP"
"1","(-6075,5125)","0","mstr_standard","I116";
;
CDS_LIB"mstr_standard"
BODY_TYPE"PLUMBING"
HDL_TAP"TRUE";
"B \NAC \NWC"8;
"S \NAC"
BN"23"136;
%"TAP"
"1","(-6075,5175)","0","mstr_standard","I117";
;
CDS_LIB"mstr_standard"
BODY_TYPE"PLUMBING"
HDL_TAP"TRUE";
"B \NAC \NWC"8;
"S \NAC"
BN"24"81;
%"TAP"
"1","(-6075,5225)","0","mstr_standard","I118";
;
CDS_LIB"mstr_standard"
BODY_TYPE"PLUMBING"
HDL_TAP"TRUE";
"B \NAC \NWC"8;
"S \NAC"
BN"25"137;
%"TAP"
"1","(-6075,5375)","0","mstr_standard","I119";
;
CDS_LIB"mstr_standard"
BODY_TYPE"PLUMBING"
HDL_TAP"TRUE";
"B \NAC \NWC"8;
"S \NAC"
BN"28"37;
%"TAP"
"1","(-6075,5325)","0","mstr_standard","I120";
;
CDS_LIB"mstr_standard"
BODY_TYPE"PLUMBING"
HDL_TAP"TRUE";
"B \NAC \NWC"8;
"S \NAC"
BN"27"139;
%"TAP"
"1","(-6075,5275)","0","mstr_standard","I121";
;
CDS_LIB"mstr_standard"
BODY_TYPE"PLUMBING"
HDL_TAP"TRUE";
"B \NAC \NWC"8;
"S \NAC"
BN"26"138;
%"TAP"
"1","(-6075,5475)","0","mstr_standard","I122";
;
CDS_LIB"mstr_standard"
BODY_TYPE"PLUMBING"
HDL_TAP"TRUE";
"B \NAC \NWC"8;
"S \NAC"
BN"30"140;
%"TAP"
"1","(-6075,5425)","0","mstr_standard","I123";
;
CDS_LIB"mstr_standard"
BODY_TYPE"PLUMBING"
HDL_TAP"TRUE";
"B \NAC \NWC"8;
"S \NAC"
BN"29"80;
%"TAP"
"1","(-6075,5525)","0","mstr_standard","I124";
;
CDS_LIB"mstr_standard"
BODY_TYPE"PLUMBING"
HDL_TAP"TRUE";
"B \NAC \NWC"8;
"S \NAC"
BN"31"79;
%"GND"
"1","(-6475,1225)","0","mstr_symbols","I126";
;
CDS_LIB"mstr_symbols"
SIZE"1B"
BOM_COST"MEM"
VOLTAGE"0.0"
BODY_TYPE"PLUMBING"
HDL_POWER"GND";
"A\NAC"1;
%"Q_RES"
"2","(-6475,1450)","0","pure_quanta","I127";
;
LOCATION"R770"
$SEC"1"
CDS_SEC"1"
WATTAGE"1/16W"
MATERIAL"CHIP"
TOLERANCE"1%"
VALUE"15.4K"
PACK_TYPE"0402LF"
CDS_LIB"pure_quanta"
PART_NUMBER"CS31542FB02";
"A"
$PN"1"172;
"B"
$PN"2"1;
%"GND"
"1","(-2175,1725)","0","mstr_symbols","I128";
;
SIZE"1B"
CDS_LIB"mstr_symbols"
VOLTAGE"0.0"
BODY_TYPE"PLUMBING"
HDL_POWER"GND";
"A\NAC"23;
%"SCONN288_DDR506112002KQ"
"3","(-1275,3475)","0","pure_quanta","I160";
;
LOCATION"J26"
$SEC"3"
CDS_SEC"3"
PART_TYPE"SMLF"
VALUE"SCONN288_DDR506112002KQ"
MATERIAL"IO"
CDS_LMAN_SYM_OUTLINE"-450,1800,450,-1750"
NEEDS_NO_SIZE"TRUE"
CDS_LIB"pure_quanta"
PART_NUMBER"DFHST8FS479";
"G3"
$PN"G3"24;
"G2"
$PN"G2"24;
"G1"
$PN"G1"24;
"VSS62"
$PN"141"24;
"VSS61"
$PN"139"24;
"VSS60"
$PN"136"24;
"VSS58"
$PN"132"24;
"VSS104"
$PN"240"23;
"VSS102"
$PN"235"23;
"VSS100"
$PN"230"23;
"VIN_BULK2"
$PN"146"26;
"VIN_BULK1"
$PN"145"26;
"VIN_BULK0"
$PN"1"26;
"VSS126"
$PN"288"23;
"VSS125"
$PN"286"23;
"VSS124"
$PN"284"23;
"VSS123"
$PN"281"23;
"VSS122"
$PN"279"23;
"VSS121"
$PN"277"23;
"VSS120"
$PN"275"23;
"VSS119"
$PN"273"23;
"VSS118"
$PN"270"23;
"VSS117"
$PN"268"23;
"VSS116"
$PN"266"23;
"VSS115"
$PN"264"23;
"VSS114"
$PN"262"23;
"VSS113"
$PN"259"23;
"VSS112"
$PN"257"23;
"VSS111"
$PN"255"23;
"VSS110"
$PN"253"23;
"VSS109"
$PN"251"23;
"VSS108"
$PN"248"23;
"VSS107"
$PN"246"23;
"VSS106"
$PN"244"23;
"VSS105"
$PN"242"23;
"VSS103"
$PN"237"23;
"VSS101"
$PN"233"23;
"VSS99"
$PN"228"23;
"VSS98"
$PN"226"23;
"VSS97"
$PN"224"23;
"VSS96"
$PN"222"23;
"VSS95"
$PN"219"23;
"VSS94"
$PN"216"23;
"VSS93"
$PN"214"23;
"VSS92"
$PN"212"23;
"VSS91"
$PN"210"23;
"VSS90"
$PN"208"23;
"VSS89"
$PN"206"23;
"VSS88"
$PN"204"23;
"VSS87"
$PN"202"23;
"VSS86"
$PN"199"23;
"VSS85"
$PN"197"23;
"VSS84"
$PN"195"23;
"VSS83"
$PN"193"23;
"VSS82"
$PN"191"23;
"VSS81"
$PN"188"23;
"VSS80"
$PN"186"23;
"VSS79"
$PN"184"23;
"VSS78"
$PN"182"23;
"VSS77"
$PN"180"23;
"VSS76"
$PN"177"23;
"VSS75"
$PN"175"23;
"VSS74"
$PN"173"23;
"VSS73"
$PN"171"23;
"VSS72"
$PN"169"23;
"VSS71"
$PN"166"23;
"VSS70"
$PN"164"23;
"VSS69"
$PN"162"23;
"VSS68"
$PN"160"23;
"VSS67"
$PN"158"23;
"VSS66"
$PN"155"23;
"VSS65"
$PN"153"23;
"VSS64"
$PN"151"23;
"VSS63"
$PN"143"24;
"VSS59"
$PN"134"24;
"VSS57"
$PN"130"24;
"VSS56"
$PN"128"24;
"VSS55"
$PN"125"24;
"VSS54"
$PN"123"24;
"VSS53"
$PN"121"24;
"VSS52"
$PN"119"24;
"VSS51"
$PN"117"24;
"VSS50"
$PN"114"24;
"VSS49"
$PN"112"24;
"VSS48"
$PN"110"24;
"VSS47"
$PN"108"24;
"VSS46"
$PN"106"24;
"VSS45"
$PN"103"24;
"VSS44"
$PN"101"24;
"VSS43"
$PN"99"24;
"VSS42"
$PN"97"24;
"VSS41"
$PN"95"24;
"VSS40"
$PN"92"24;
"VSS39"
$PN"90"24;
"VSS38"
$PN"88"24;
"VSS37"
$PN"85"24;
"VSS36"
$PN"83"24;
"VSS35"
$PN"81"24;
"VSS34"
$PN"79"24;
"VSS33"
$PN"77"24;
"VSS32"
$PN"75"24;
"VSS31"
$PN"73"24;
"VSS30"
$PN"71"24;
"VSS29"
$PN"69"24;
"VSS28"
$PN"67"24;
"VSS27"
$PN"65"24;
"VSS26"
$PN"63"24;
"VSS25"
$PN"61"24;
"VSS24"
$PN"59"24;
"VSS23"
$PN"57"24;
"VSS22"
$PN"54"24;
"VSS21"
$PN"52"24;
"VSS20"
$PN"50"24;
"VSS19"
$PN"48"24;
"VSS18"
$PN"46"24;
"VSS17"
$PN"43"24;
"VSS16"
$PN"41"24;
"VSS15"
$PN"39"24;
"VSS14"
$PN"37"24;
"VSS13"
$PN"35"24;
"VSS12"
$PN"32"24;
"VSS11"
$PN"30"24;
"VSS10"
$PN"28"24;
"VSS9"
$PN"26"24;
"VSS8"
$PN"24"24;
"VSS7"
$PN"21"24;
"VSS6"
$PN"19"24;
"VSS5"
$PN"17"24;
"VSS4"
$PN"15"24;
"VSS3"
$PN"13"24;
"VSS2"
$PN"10"24;
"VSS1"
$PN"8"24;
"VSS0"
$PN"6"24;
%"GND"
"1","(-375,1550)","0","mstr_symbols","I161";
;
CDS_LIB"mstr_symbols"
SIZE"1B"
VOLTAGE"0.0"
BODY_TYPE"PLUMBING"
HDL_POWER"GND";
"A\NAC"24;
%"Q_CAP"
"1","(-8725,3325)","2","pure_quanta","I185";
;
LOCATION"C140"
$SEC"1"
CDS_SEC"1"
PACK_TYPE"0402"
VALUE"0.1UF"
VOLTAGE"25V"
TOLERANCE"10%"
MATERIAL"X7R"
CDS_LIB"pure_quanta"
BOM_COST"MEM"
ROOM""
PART_NUMBER"CH4104K1B00";
"B"
$PN"2"2;
"A"
$PN"1"14;
%"GND"
"1","(-8725,3100)","0","mstr_symbols","I186";
;
BOM_COST"MEM"
SIZE"1B"
CDS_LIB"mstr_symbols"
VOLTAGE"0"
ROOM"MEM_EFGH_DECOUPLING_CAPS"
BODY_TYPE"PLUMBING"
HDL_POWER"GND";
"A\NAC"2;
%"Q_RES"
"1","(-8625,2275)","2","pure_quanta","I188";
;
LOCATION"R304"
$SEC"1"
CDS_SEC"1"
VALUE"1K"
TOLERANCE"1%"
BOM_COST"MEM"
CDS_LIB"pure_quanta"
WATTAGE"1/16W"
MATERIAL"CHIP"
PACK_TYPE"0402LF"
ROOM""
PART_NUMBER"CS21002FB06";
"B"
$PN"2"32;
"A"
$PN"1"15;
%"VCC_CORE"
"1","(-8500,2600)","0","mstr_symbols","I189";
;
HDL_POWER"P3V3"
CDS_LIB"mstr_symbols"
VOLTAGE"3.3"
ROOM"PVCCINFAON_CPU0_CTRL";
"A"3;
%"Q_RES"
"2","(-8500,2425)","0","pure_quanta","I190";
;
LOCATION"R104"
$SEC"1"
CDS_SEC"1"
TOLERANCE"1%"
MATERIAL"EMPTY"
WATTAGE"1/16W"
VALUE"1K"
PACK_TYPE"0402LF"
CDS_LIB"pure_quanta"
BOM_COST"MEM"
ROOM""
PART_NUMBER"CS21002FB06";
"A"
$PN"1"3;
"B"
$PN"2"15;
%"TAP"
"1","(-3250,3750)","0","mstr_standard","I191";
;
CDS_LIB"mstr_standard"
BODY_TYPE"PLUMBING"
HDL_TAP"TRUE";
"B \NAC \NWC"10;
"S \NAC"
BN"2"63;
%"TAP"
"1","(-3250,4450)","0","mstr_standard","I195";
;
CDS_LIB"mstr_standard"
BODY_TYPE"PLUMBING"
HDL_TAP"TRUE";
"B \NAC \NWC"10;
"S \NAC"
BN"9"42;
%"TAP"
"1","(-3250,4350)","0","mstr_standard","I196";
;
CDS_LIB"mstr_standard"
BODY_TYPE"PLUMBING"
HDL_TAP"TRUE";
"B \NAC \NWC"10;
"S \NAC"
BN"8"36;
%"TAP"
"1","(-3250,4250)","0","mstr_standard","I197";
;
CDS_LIB"mstr_standard"
BODY_TYPE"PLUMBING"
HDL_TAP"TRUE";
"B \NAC \NWC"10;
"S \NAC"
BN"7"76;
%"TAP"
"1","(-3250,4150)","0","mstr_standard","I198";
;
CDS_LIB"mstr_standard"
BODY_TYPE"PLUMBING"
HDL_TAP"TRUE";
"B \NAC \NWC"10;
"S \NAC"
BN"6"47;
%"TAP"
"1","(-3250,4050)","0","mstr_standard","I199";
;
CDS_LIB"mstr_standard"
BODY_TYPE"PLUMBING"
HDL_TAP"TRUE";
"B \NAC \NWC"10;
"S \NAC"
BN"5"51;
%"TAP"
"1","(-3450,4400)","0","mstr_standard","I200";
;
CDS_LIB"mstr_standard"
BODY_TYPE"PLUMBING"
HDL_TAP"TRUE";
"B \NAC \NWC"11;
"S \NAC"
BN"8"43;
%"TAP"
"1","(-3450,4500)","0","mstr_standard","I201";
;
CDS_LIB"mstr_standard"
BODY_TYPE"PLUMBING"
HDL_TAP"TRUE";
"B \NAC \NWC"11;
"S \NAC"
BN"9"39;
%"TAP"
"1","(-3450,4300)","0","mstr_standard","I202";
;
CDS_LIB"mstr_standard"
BODY_TYPE"PLUMBING"
HDL_TAP"TRUE";
"B \NAC \NWC"11;
"S \NAC"
BN"7"35;
%"TAP"
"1","(-3450,4100)","0","mstr_standard","I203";
;
CDS_LIB"mstr_standard"
BODY_TYPE"PLUMBING"
HDL_TAP"TRUE";
"B \NAC \NWC"11;
"S \NAC"
BN"5"50;
%"TAP"
"1","(-3450,4200)","0","mstr_standard","I204";
;
CDS_LIB"mstr_standard"
BODY_TYPE"PLUMBING"
HDL_TAP"TRUE";
"B \NAC \NWC"11;
"S \NAC"
BN"6"75;
%"TAP"
"1","(-3250,3950)","0","mstr_standard","I207";
;
CDS_LIB"mstr_standard"
BODY_TYPE"PLUMBING"
HDL_TAP"TRUE";
"B \NAC \NWC"10;
"S \NAC"
BN"4"55;
%"TAP"
"1","(-3250,3850)","0","mstr_standard","I208";
;
CDS_LIB"mstr_standard"
BODY_TYPE"PLUMBING"
HDL_TAP"TRUE";
"B \NAC \NWC"10;
"S \NAC"
BN"3"59;
%"TAP"
"1","(-3250,3550)","0","mstr_standard","I209";
;
CDS_LIB"mstr_standard"
BODY_TYPE"PLUMBING"
HDL_TAP"TRUE";
"B \NAC \NWC"10;
"S \NAC"
BN"0"71;
%"TAP"
"1","(-3250,3650)","0","mstr_standard","I210";
;
CDS_LIB"mstr_standard"
BODY_TYPE"PLUMBING"
HDL_TAP"TRUE";
"B \NAC \NWC"10;
"S \NAC"
BN"1"67;
%"TAP"
"1","(-3250,3300)","0","mstr_standard","I211";
;
CDS_LIB"mstr_standard"
BODY_TYPE"PLUMBING"
HDL_TAP"TRUE";
"B \NAC \NWC"13;
"S \NAC"
BN"8"73;
%"TAP"
"1","(-3250,3400)","0","mstr_standard","I212";
;
CDS_LIB"mstr_standard"
BODY_TYPE"PLUMBING"
HDL_TAP"TRUE";
"B \NAC \NWC"13;
"S \NAC"
BN"9"41;
%"TAP"
"1","(-3250,3200)","0","mstr_standard","I213";
;
CDS_LIB"mstr_standard"
BODY_TYPE"PLUMBING"
HDL_TAP"TRUE";
"B \NAC \NWC"13;
"S \NAC"
BN"7"44;
%"TAP"
"1","(-3250,3100)","0","mstr_standard","I214";
;
CDS_LIB"mstr_standard"
BODY_TYPE"PLUMBING"
HDL_TAP"TRUE";
"B \NAC \NWC"13;
"S \NAC"
BN"6"46;
%"TAP"
"1","(-3450,3900)","0","mstr_standard","I215";
;
CDS_LIB"mstr_standard"
BODY_TYPE"PLUMBING"
HDL_TAP"TRUE";
"B \NAC \NWC"11;
"S \NAC"
BN"3"58;
%"TAP"
"1","(-3450,4000)","0","mstr_standard","I216";
;
CDS_LIB"mstr_standard"
BODY_TYPE"PLUMBING"
HDL_TAP"TRUE";
"B \NAC \NWC"11;
"S \NAC"
BN"4"54;
%"TAP"
"1","(-3450,3800)","0","mstr_standard","I217";
;
CDS_LIB"mstr_standard"
BODY_TYPE"PLUMBING"
HDL_TAP"TRUE";
"B \NAC \NWC"11;
"S \NAC"
BN"2"62;
%"TAP"
"1","(-3450,3700)","0","mstr_standard","I218";
;
CDS_LIB"mstr_standard"
BODY_TYPE"PLUMBING"
HDL_TAP"TRUE";
"B \NAC \NWC"11;
"S \NAC"
BN"1"66;
%"TAP"
"1","(-3450,3600)","0","mstr_standard","I219";
;
CDS_LIB"mstr_standard"
BODY_TYPE"PLUMBING"
HDL_TAP"TRUE";
"B \NAC \NWC"11;
"S \NAC"
BN"0"70;
%"SCONN288_DDR506112002KQ"
"1","(-6925,3775)","0","pure_quanta","I22";
;
LOCATION"J26"
$SEC"1"
CDS_SEC"1"
PART_TYPE"SMLF"
VALUE"SCONN288_DDR506112002KQ"
MATERIAL"IO"
CDS_LMAN_SYM_OUTLINE"-450,1900,450,-1850"
NEEDS_NO_SIZE"TRUE"
CDS_LIB"pure_quanta"
PART_NUMBER"DFHST8FS479";
"PWR_GOOD||FAIL_N"
$PN"147"15;
"DQ31_A"
$PN"194"79;
"CB7_A"
$PN"205"171;
"CB4_A"
$PN"58"170;
"CB1_A"
$PN"53"169;
"CB7_B"
$PN"236"168;
"ALERT_N \B"
$PN"62"27;
"CA0_A"
$PN"66"34;
"CA0_B"
$PN"76"167;
"CA1_A"
$PN"211"77;
"CA1_B"
$PN"221"166;
"CA2_A"
$PN"68"165;
"CA2_B"
$PN"78"164;
"CA3_A"
$PN"213"163;
"CA3_B"
$PN"223"162;
"CA4_A"
$PN"70"78;
"CA4_B"
$PN"80"161;
"CA5_A"
$PN"215"160;
"CA5_B"
$PN"225"159;
"CA6_A"
$PN"72"158;
"CA6_B"
$PN"82"157;
"CB6_A"
$PN"203"156;
"CB5_A"
$PN"60"155;
"CB3_A"
$PN"198"154;
"CB2_A"
$PN"196"153;
"CB0_A"
$PN"51"152;
"CB6_B"
$PN"234"151;
"CB5_B"
$PN"91"150;
"CB4_B"
$PN"89"149;
"CB3_B"
$PN"243"148;
"CB2_B"
$PN"241"29;
"CB1_B"
$PN"98"30;
"CB0_B"
$PN"96"147;
"CK_C \B"
$PN"218"146;
"CK_T"
$PN"217"145;
"CS0_A_N"
$PN"64"144;
"CS0_B_N"
$PN"84"143;
"CS1_A_N"
$PN"209"142;
"CS1_B_N"
$PN"229"141;
"DQ30_A"
$PN"192"140;
"DQ29_A"
$PN"49"80;
"DQ28_A"
$PN"47"37;
"DQ27_A"
$PN"187"139;
"DQ26_A"
$PN"185"138;
"DQ25_A"
$PN"42"137;
"DQ24_A"
$PN"40"81;
"DQ23_A"
$PN"183"136;
"DQ22_A"
$PN"181"135;
"DQ21_A"
$PN"38"134;
"DQ20_A"
$PN"36"133;
"DQ19_A"
$PN"176"38;
"DQ18_A"
$PN"174"132;
"DQ17_A"
$PN"31"131;
"DQ16_A"
$PN"29"130;
"DQ15_A"
$PN"172"129;
"DQ14_A"
$PN"170"128;
"DQ13_A"
$PN"27"127;
"DQ12_A"
$PN"25"126;
"DQ11_A"
$PN"165"125;
"DQ10_A"
$PN"163"124;
"DQ9_A"
$PN"20"123;
"DQ8_A"
$PN"18"122;
"DQ7_A"
$PN"161"121;
"DQ6_A"
$PN"159"120;
"DQ5_A"
$PN"16"119;
"DQ4_A"
$PN"14"118;
"DQ3_A"
$PN"154"117;
"DQ2_A"
$PN"152"116;
"DQ1_A"
$PN"9"115;
"DQ0_A"
$PN"7"114;
"DQ31_B"
$PN"287"113;
"DQ30_B"
$PN"285"112;
"DQ29_B"
$PN"142"111;
"DQ28_B"
$PN"140"110;
"DQ27_B"
$PN"280"22;
"DQ26_B"
$PN"278"109;
"DQ25_B"
$PN"135"108;
"DQ24_B"
$PN"133"107;
"DQ23_B"
$PN"276"106;
"DQ22_B"
$PN"274"31;
"DQ21_B"
$PN"131"105;
"DQ20_B"
$PN"129"104;
"DQ19_B"
$PN"269"103;
"DQ18_B"
$PN"267"102;
"DQ17_B"
$PN"124"101;
"DQ16_B"
$PN"122"100;
"DQ15_B"
$PN"265"99;
"DQ14_B"
$PN"263"98;
"DQ13_B"
$PN"120"97;
"DQ12_B"
$PN"118"96;
"DQ11_B"
$PN"258"95;
"DQ10_B"
$PN"256"94;
"DQ9_B"
$PN"113"93;
"DQ8_B"
$PN"111"92;
"DQ7_B"
$PN"254"91;
"DQ6_B"
$PN"252"90;
"DQ5_B"
$PN"109"89;
"DQ4_B"
$PN"107"88;
"DQ3_B"
$PN"247"87;
"DQ2_B"
$PN"245"33;
"DQ1_B"
$PN"102"86;
"DQ0_B"
$PN"100"85;
"HAS"
$PN"148"19;
"HSCL"
$PN"4"20;
"HSDA"
$PN"5"16;
"LBD||RSP_A_N"
$PN"86"84;
"LBS||RSP_B_N"
$PN"87"21;
"PAR_A"
$PN"74"83;
"PAR_B"
$PN"227"82;
"RESET_N \B"
$PN"207"28;
"RFU6"
$PN"232"0;
"RFU5"
$PN"231"0;
"RFU4"
$PN"220"0;
"RFU3"
$PN"150"0;
"RFU2"
$PN"149"0;
"RFU1"
$PN"144"0;
"RFU0"
$PN"2"0;
"VIN_MGMT"
$PN"3"14;
%"TAP"
"1","(-3450,3350)","0","mstr_standard","I220";
;
CDS_LIB"mstr_standard"
BODY_TYPE"PLUMBING"
HDL_TAP"TRUE";
"B \NAC \NWC"12;
"S \NAC"
BN"8"74;
%"TAP"
"1","(-3450,3450)","0","mstr_standard","I221";
;
CDS_LIB"mstr_standard"
BODY_TYPE"PLUMBING"
HDL_TAP"TRUE";
"B \NAC \NWC"12;
"S \NAC"
BN"9"40;
%"TAP"
"1","(-3450,3250)","0","mstr_standard","I222";
;
CDS_LIB"mstr_standard"
BODY_TYPE"PLUMBING"
HDL_TAP"TRUE";
"B \NAC \NWC"12;
"S \NAC"
BN"7"72;
%"TAP"
"1","(-3450,3150)","0","mstr_standard","I223";
;
CDS_LIB"mstr_standard"
BODY_TYPE"PLUMBING"
HDL_TAP"TRUE";
"B \NAC \NWC"12;
"S \NAC"
BN"6"45;
%"TAP"
"1","(-3450,3050)","0","mstr_standard","I224";
;
CDS_LIB"mstr_standard"
BODY_TYPE"PLUMBING"
HDL_TAP"TRUE";
"B \NAC \NWC"12;
"S \NAC"
BN"5"48;
%"TAP"
"1","(-3250,3000)","0","mstr_standard","I225";
;
CDS_LIB"mstr_standard"
BODY_TYPE"PLUMBING"
HDL_TAP"TRUE";
"B \NAC \NWC"13;
"S \NAC"
BN"5"49;
%"TAP"
"1","(-3250,2900)","0","mstr_standard","I226";
;
CDS_LIB"mstr_standard"
BODY_TYPE"PLUMBING"
HDL_TAP"TRUE";
"B \NAC \NWC"13;
"S \NAC"
BN"4"53;
%"TAP"
"1","(-3250,2800)","0","mstr_standard","I227";
;
CDS_LIB"mstr_standard"
BODY_TYPE"PLUMBING"
HDL_TAP"TRUE";
"B \NAC \NWC"13;
"S \NAC"
BN"3"57;
%"TAP"
"1","(-3250,2700)","0","mstr_standard","I228";
;
CDS_LIB"mstr_standard"
BODY_TYPE"PLUMBING"
HDL_TAP"TRUE";
"B \NAC \NWC"13;
"S \NAC"
BN"2"61;
%"TAP"
"1","(-3250,2600)","0","mstr_standard","I229";
;
CDS_LIB"mstr_standard"
BODY_TYPE"PLUMBING"
HDL_TAP"TRUE";
"B \NAC \NWC"13;
"S \NAC"
BN"1"65;
%"TAP"
"1","(-7775,3325)","2","mstr_standard","I23";
;
CDS_LIB"mstr_standard"
BODY_TYPE"PLUMBING"
HDL_TAP"TRUE";
"B \NAC \NWC"5;
"S \NAC"
BN"0"147;
%"TAP"
"1","(-3250,2500)","0","mstr_standard","I230";
;
CDS_LIB"mstr_standard"
BODY_TYPE"PLUMBING"
HDL_TAP"TRUE";
"B \NAC \NWC"13;
"S \NAC"
BN"0"69;
%"TAP"
"1","(-3450,2850)","0","mstr_standard","I231";
;
CDS_LIB"mstr_standard"
BODY_TYPE"PLUMBING"
HDL_TAP"TRUE";
"B \NAC \NWC"12;
"S \NAC"
BN"3"56;
%"TAP"
"1","(-3450,2950)","0","mstr_standard","I232";
;
CDS_LIB"mstr_standard"
BODY_TYPE"PLUMBING"
HDL_TAP"TRUE";
"B \NAC \NWC"12;
"S \NAC"
BN"4"52;
%"TAP"
"1","(-3450,2750)","0","mstr_standard","I233";
;
CDS_LIB"mstr_standard"
BODY_TYPE"PLUMBING"
HDL_TAP"TRUE";
"B \NAC \NWC"12;
"S \NAC"
BN"2"60;
%"TAP"
"1","(-3450,2550)","0","mstr_standard","I234";
;
CDS_LIB"mstr_standard"
BODY_TYPE"PLUMBING"
HDL_TAP"TRUE";
"B \NAC \NWC"12;
"S \NAC"
BN"0"68;
%"TAP"
"1","(-3450,2650)","0","mstr_standard","I235";
;
CDS_LIB"mstr_standard"
BODY_TYPE"PLUMBING"
HDL_TAP"TRUE";
"B \NAC \NWC"12;
"S \NAC"
BN"1"64;
%"SCONN288_DDR506112002KQ"
"2","(-4400,3500)","0","pure_quanta","I236";
;
LOCATION"J26"
$SEC"2"
CDS_SEC"2"
VALUE"SCONN288_DDR506112002KQ"
PART_TYPE"SMLF"
MATERIAL"IO"
CDS_LMAN_SYM_OUTLINE"-600,1150,600,-1150"
NEEDS_NO_SIZE"TRUE"
CDS_LIB"pure_quanta"
PART_NUMBER"DFHST8FS479";
"DQS7_A_C||TDQS7_A_C \B"
$PN"178"76;
"DQS6_A_T||TDQS6_A_T"
$PN"168"75;
"DQS8_B_T||TDQS8_B_T"
$PN"283"74;
"DQS8_B_C||TDQS8_B_C \B"
$PN"282"73;
"DQS7_B_T||TDQS7_B_T"
$PN"272"72;
"DQS0_A_C \B"
$PN"12"71;
"DQS0_A_T"
$PN"11"70;
"DQS0_B_C \B"
$PN"105"69;
"DQS0_B_T"
$PN"104"68;
"DQS1_A_C \B"
$PN"23"67;
"DQS1_A_T"
$PN"22"66;
"DQS1_B_C \B"
$PN"116"65;
"DQS1_B_T"
$PN"115"64;
"DQS2_A_C \B"
$PN"34"63;
"DQS2_A_T"
$PN"33"62;
"DQS2_B_C \B"
$PN"127"61;
"DQS2_B_T"
$PN"126"60;
"DQS3_A_C \B"
$PN"45"59;
"DQS3_A_T"
$PN"44"58;
"DQS3_B_C \B"
$PN"138"57;
"DQS3_B_T"
$PN"137"56;
"DQS4_A_C \B"
$PN"56"55;
"DQS4_A_T"
$PN"55"54;
"DQS4_B_C \B"
$PN"238"53;
"DQS4_B_T"
$PN"239"52;
"DQS5_A_C||TDQS5_A_C||DQS5_A_T||TDQS5_A_T \B"
$PN"156"51;
"DQS5_A_T||TDQS5_A_T"
$PN"157"50;
"DQS5_B_C||TDQS5_B_C \B"
$PN"249"49;
"DQS5_B_T||TDQS5_B_T"
$PN"250"48;
"DQS6_A_C||TDQS6_A_C||DQS6_A_T||TDQS6_A_T \B"
$PN"167"47;
"DQS6_B_C||TDQS6_B_C \B"
$PN"260"46;
"DQS6_B_T||TDQS6_B_T"
$PN"261"45;
"DQS7_A_T||TDQS7_A_T"
$PN"179"35;
"DQS7_B_C||TDQS7_B_C \B"
$PN"271"44;
"DQS8_A_C||TDQS8_A_C \B"
$PN"189"36;
"DQS8_A_T||TDQS8_A_T"
$PN"190"43;
"DQS9_A_C||TDQS9_A_C \B"
$PN"200"42;
"DQS9_A_T||TDQS9_A_T"
$PN"201"39;
"DQS9_B_C||TDQS9_B_C \B"
$PN"94"41;
"DQS9_B_T||TDQS9_B_T||DBI4_B_N"
$PN"93"40;
%"GND"
"1","(-2875,5175)","0","pure_quanta_power","I237";
;
CDS_LIB"pure_quanta_power"
BOM_COST"MEM"
SIZE"1B"
ROOM"MEM_EFGH_DECOUPLING_CAPS"
HDL_POWER"GND";
"A<SIZE-1..0>\NAC"25;
%"Q_CAP"
"1","(-2875,5525)","2","pure_quanta","I238";
;
LOCATION"C175"
$SEC"1"
CDS_SEC"1"
PACK_TYPE"C0805"
TOLERANCE"10%"
MATERIAL"X6S"
VALUE"10UF"
VOLTAGE"25V"
CDS_LIB"pure_quanta"
BOM_COST"MEM"
ROOM""
PART_NUMBER"CH6104KEA00";
"B"
$PN"2"25;
"A"
$PN"1"26;
%"Q_CAP"
"1","(-2300,5525)","2","pure_quanta","I239";
;
LOCATION"C177"
$SEC"1"
CDS_SEC"1"
VALUE"10UF"
VOLTAGE"25V"
TOLERANCE"10%"
PACK_TYPE"C0805"
MATERIAL"X6S"
CDS_LIB"pure_quanta"
BOM_COST"MEM"
ROOM""
PART_NUMBER"CH6104KEA00";
"B"
$PN"2"25;
"A"
$PN"1"26;
%"TAP"
"1","(-7775,3375)","2","mstr_standard","I24";
;
CDS_LIB"mstr_standard"
BODY_TYPE"PLUMBING"
HDL_TAP"TRUE";
"B \NAC \NWC"5;
"S \NAC"
BN"1"30;
%"UNIVERSAL_POWER"
"1","(-2875,5850)","0","pure_quanta_power","I240";
;
HDL_POWER"P12V_MEM_CPU1"
CDS_LIB"pure_quanta_power";
"A"26;
%"Q_RES"
"1","(-7825,2750)","0","pure_quanta","I242";
;
LOCATION"R1581"
$SEC"1"
CDS_SEC"1"
VALUE"49.9"
CDS_LIB"pure_quanta"
MATERIAL"CHIP"
PACK_TYPE"0402LF"
WATTAGE"1/16W"
TOLERANCE"1%"
PART_NUMBER"CS04992FB07";
"B"
$PN"2"20;
"A"
$PN"1"17;
%"Q_RES"
"1","(-8200,2975)","0","pure_quanta","I243";
;
LOCATION"R1696"
$SEC"1"
CDS_SEC"1"
PACK_TYPE"0402LF"
MATERIAL"CHIP"
VALUE"10"
TOLERANCE"1%"
WATTAGE"1/16W"
CDS_LIB"pure_quanta"
PART_NUMBER"CS01002FB07";
"B"
$PN"2"16;
"A"
$PN"1"18;
%"TAP"
"1","(-7775,3425)","2","mstr_standard","I25";
;
CDS_LIB"mstr_standard"
BODY_TYPE"PLUMBING"
HDL_TAP"TRUE";
"B \NAC \NWC"5;
"S \NAC"
BN"2"29;
%"TAP"
"1","(-7775,3525)","2","mstr_standard","I26";
;
CDS_LIB"mstr_standard"
BODY_TYPE"PLUMBING"
HDL_TAP"TRUE";
"B \NAC \NWC"5;
"S \NAC"
BN"4"149;
%"TAP"
"1","(-7775,3475)","2","mstr_standard","I27";
;
CDS_LIB"mstr_standard"
BODY_TYPE"PLUMBING"
HDL_TAP"TRUE";
"B \NAC \NWC"5;
"S \NAC"
BN"3"148;
%"TAP"
"1","(-7775,3575)","2","mstr_standard","I28";
;
CDS_LIB"mstr_standard"
BODY_TYPE"PLUMBING"
HDL_TAP"TRUE";
"B \NAC \NWC"5;
"S \NAC"
BN"5"150;
%"TAP"
"1","(-7775,3675)","2","mstr_standard","I29";
;
CDS_LIB"mstr_standard"
BODY_TYPE"PLUMBING"
HDL_TAP"TRUE";
"B \NAC \NWC"5;
"S \NAC"
BN"7"168;
%"TAP"
"1","(-7775,3625)","2","mstr_standard","I30";
;
CDS_LIB"mstr_standard"
BODY_TYPE"PLUMBING"
HDL_TAP"TRUE";
"B \NAC \NWC"5;
"S \NAC"
BN"6"151;
%"TAP"
"1","(-7775,3775)","2","mstr_standard","I31";
;
CDS_LIB"mstr_standard"
BODY_TYPE"PLUMBING"
HDL_TAP"TRUE";
"B \NAC \NWC"4;
"S \NAC"
BN"0"152;
%"TAP"
"1","(-7775,3825)","2","mstr_standard","I32";
;
CDS_LIB"mstr_standard"
BODY_TYPE"PLUMBING"
HDL_TAP"TRUE";
"B \NAC \NWC"4;
"S \NAC"
BN"1"169;
%"TAP"
"1","(-7775,3875)","2","mstr_standard","I33";
;
CDS_LIB"mstr_standard"
BODY_TYPE"PLUMBING"
HDL_TAP"TRUE";
"B \NAC \NWC"4;
"S \NAC"
BN"2"153;
%"TAP"
"1","(-7775,3925)","2","mstr_standard","I34";
;
CDS_LIB"mstr_standard"
BODY_TYPE"PLUMBING"
HDL_TAP"TRUE";
"B \NAC \NWC"4;
"S \NAC"
BN"3"154;
%"TAP"
"1","(-7775,4025)","2","mstr_standard","I35";
;
CDS_LIB"mstr_standard"
BODY_TYPE"PLUMBING"
HDL_TAP"TRUE";
"B \NAC \NWC"4;
"S \NAC"
BN"5"155;
%"TAP"
"1","(-7775,3975)","2","mstr_standard","I36";
;
CDS_LIB"mstr_standard"
BODY_TYPE"PLUMBING"
HDL_TAP"TRUE";
"B \NAC \NWC"4;
"S \NAC"
BN"4"170;
%"TAP"
"1","(-7775,4075)","2","mstr_standard","I37";
;
CDS_LIB"mstr_standard"
BODY_TYPE"PLUMBING"
HDL_TAP"TRUE";
"B \NAC \NWC"4;
"S \NAC"
BN"6"156;
%"TAP"
"1","(-6075,2375)","0","mstr_standard","I38";
;
CDS_LIB"mstr_standard"
BODY_TYPE"PLUMBING"
HDL_TAP"TRUE";
"B \NAC \NWC"9;
"S \NAC"
BN"1"86;
%"TAP"
"1","(-6075,2325)","0","mstr_standard","I39";
;
CDS_LIB"mstr_standard"
BODY_TYPE"PLUMBING"
HDL_TAP"TRUE";
"B \NAC \NWC"9;
"S \NAC"
BN"0"85;
%"TAP"
"1","(-6075,2425)","0","mstr_standard","I40";
;
CDS_LIB"mstr_standard"
BODY_TYPE"PLUMBING"
HDL_TAP"TRUE";
"B \NAC \NWC"9;
"S \NAC"
BN"2"33;
%"TAP"
"1","(-6075,2475)","0","mstr_standard","I41";
;
CDS_LIB"mstr_standard"
BODY_TYPE"PLUMBING"
HDL_TAP"TRUE";
"B \NAC \NWC"9;
"S \NAC"
BN"3"87;
%"TAP"
"1","(-6075,2525)","0","mstr_standard","I42";
;
CDS_LIB"mstr_standard"
BODY_TYPE"PLUMBING"
HDL_TAP"TRUE";
"B \NAC \NWC"9;
"S \NAC"
BN"4"88;
%"TAP"
"1","(-6075,2575)","0","mstr_standard","I43";
;
CDS_LIB"mstr_standard"
BODY_TYPE"PLUMBING"
HDL_TAP"TRUE";
"B \NAC \NWC"9;
"S \NAC"
BN"5"89;
%"TAP"
"1","(-6075,2675)","0","mstr_standard","I44";
;
CDS_LIB"mstr_standard"
BODY_TYPE"PLUMBING"
HDL_TAP"TRUE";
"B \NAC \NWC"9;
"S \NAC"
BN"7"91;
%"TAP"
"1","(-6075,2625)","0","mstr_standard","I45";
;
CDS_LIB"mstr_standard"
BODY_TYPE"PLUMBING"
HDL_TAP"TRUE";
"B \NAC \NWC"9;
"S \NAC"
BN"6"90;
%"TAP"
"1","(-6075,2775)","0","mstr_standard","I46";
;
CDS_LIB"mstr_standard"
BODY_TYPE"PLUMBING"
HDL_TAP"TRUE";
"B \NAC \NWC"9;
"S \NAC"
BN"9"93;
%"TAP"
"1","(-6075,2725)","0","mstr_standard","I47";
;
CDS_LIB"mstr_standard"
BODY_TYPE"PLUMBING"
HDL_TAP"TRUE";
"B \NAC \NWC"9;
"S \NAC"
BN"8"92;
%"TAP"
"1","(-6075,2975)","0","mstr_standard","I48";
;
CDS_LIB"mstr_standard"
BODY_TYPE"PLUMBING"
HDL_TAP"TRUE";
"B \NAC \NWC"9;
"S \NAC"
BN"13"97;
%"TAP"
"1","(-6075,3025)","0","mstr_standard","I49";
;
CDS_LIB"mstr_standard"
BODY_TYPE"PLUMBING"
HDL_TAP"TRUE";
"B \NAC \NWC"9;
"S \NAC"
BN"14"98;
%"TAP"
"1","(-6075,2925)","0","mstr_standard","I50";
;
CDS_LIB"mstr_standard"
BODY_TYPE"PLUMBING"
HDL_TAP"TRUE";
"B \NAC \NWC"9;
"S \NAC"
BN"12"96;
%"TAP"
"1","(-6075,2875)","0","mstr_standard","I51";
;
CDS_LIB"mstr_standard"
BODY_TYPE"PLUMBING"
HDL_TAP"TRUE";
"B \NAC \NWC"9;
"S \NAC"
BN"11"95;
%"TAP"
"1","(-6075,2825)","0","mstr_standard","I52";
;
CDS_LIB"mstr_standard"
BODY_TYPE"PLUMBING"
HDL_TAP"TRUE";
"B \NAC \NWC"9;
"S \NAC"
BN"10"94;
%"TAP"
"1","(-6075,3075)","0","mstr_standard","I53";
;
CDS_LIB"mstr_standard"
BODY_TYPE"PLUMBING"
HDL_TAP"TRUE";
"B \NAC \NWC"9;
"S \NAC"
BN"15"99;
%"TAP"
"1","(-6075,3175)","0","mstr_standard","I54";
;
CDS_LIB"mstr_standard"
BODY_TYPE"PLUMBING"
HDL_TAP"TRUE";
"B \NAC \NWC"9;
"S \NAC"
BN"17"101;
%"TAP"
"1","(-6075,3125)","0","mstr_standard","I55";
;
CDS_LIB"mstr_standard"
BODY_TYPE"PLUMBING"
HDL_TAP"TRUE";
"B \NAC \NWC"9;
"S \NAC"
BN"16"100;
%"TAP"
"1","(-6075,3225)","0","mstr_standard","I56";
;
CDS_LIB"mstr_standard"
BODY_TYPE"PLUMBING"
HDL_TAP"TRUE";
"B \NAC \NWC"9;
"S \NAC"
BN"18"102;
%"TAP"
"1","(-6075,3275)","0","mstr_standard","I57";
;
CDS_LIB"mstr_standard"
BODY_TYPE"PLUMBING"
HDL_TAP"TRUE";
"B \NAC \NWC"9;
"S \NAC"
BN"19"103;
%"TAP"
"1","(-6075,3325)","0","mstr_standard","I58";
;
CDS_LIB"mstr_standard"
BODY_TYPE"PLUMBING"
HDL_TAP"TRUE";
"B \NAC \NWC"9;
"S \NAC"
BN"20"104;
%"TAP"
"1","(-6075,3475)","0","mstr_standard","I59";
;
CDS_LIB"mstr_standard"
BODY_TYPE"PLUMBING"
HDL_TAP"TRUE";
"B \NAC \NWC"9;
"S \NAC"
BN"23"106;
%"TAP"
"1","(-6075,3525)","0","mstr_standard","I60";
;
CDS_LIB"mstr_standard"
BODY_TYPE"PLUMBING"
HDL_TAP"TRUE";
"B \NAC \NWC"9;
"S \NAC"
BN"24"107;
%"TAP"
"1","(-6075,3575)","0","mstr_standard","I61";
;
CDS_LIB"mstr_standard"
BODY_TYPE"PLUMBING"
HDL_TAP"TRUE";
"B \NAC \NWC"9;
"S \NAC"
BN"25"108;
%"TAP"
"1","(-6075,3425)","0","mstr_standard","I62";
;
CDS_LIB"mstr_standard"
BODY_TYPE"PLUMBING"
HDL_TAP"TRUE";
"B \NAC \NWC"9;
"S \NAC"
BN"22"31;
%"TAP"
"1","(-6075,3375)","0","mstr_standard","I63";
;
CDS_LIB"mstr_standard"
BODY_TYPE"PLUMBING"
HDL_TAP"TRUE";
"B \NAC \NWC"9;
"S \NAC"
BN"21"105;
%"TAP"
"1","(-6075,3725)","0","mstr_standard","I64";
;
CDS_LIB"mstr_standard"
BODY_TYPE"PLUMBING"
HDL_TAP"TRUE";
"B \NAC \NWC"9;
"S \NAC"
BN"28"110;
%"TAP"
"1","(-6075,3825)","0","mstr_standard","I65";
;
CDS_LIB"mstr_standard"
BODY_TYPE"PLUMBING"
HDL_TAP"TRUE";
"B \NAC \NWC"9;
"S \NAC"
BN"30"112;
%"TAP"
"1","(-6075,3775)","0","mstr_standard","I66";
;
CDS_LIB"mstr_standard"
BODY_TYPE"PLUMBING"
HDL_TAP"TRUE";
"B \NAC \NWC"9;
"S \NAC"
BN"29"111;
%"TAP"
"1","(-6075,3675)","0","mstr_standard","I67";
;
CDS_LIB"mstr_standard"
BODY_TYPE"PLUMBING"
HDL_TAP"TRUE";
"B \NAC \NWC"9;
"S \NAC"
BN"27"22;
%"TAP"
"1","(-6075,3625)","0","mstr_standard","I68";
;
CDS_LIB"mstr_standard"
BODY_TYPE"PLUMBING"
HDL_TAP"TRUE";
"B \NAC \NWC"9;
"S \NAC"
BN"26"109;
%"TAP"
"1","(-6075,3875)","0","mstr_standard","I69";
;
CDS_LIB"mstr_standard"
BODY_TYPE"PLUMBING"
HDL_TAP"TRUE";
"B \NAC \NWC"9;
"S \NAC"
BN"31"113;
%"VCC_CORE"
"1","(-8625,3550)","0","mstr_symbols","I7";
;
HDL_POWER"P3V3_AUX"
CDS_LIB"mstr_symbols"
VOLTAGE"3.3"
ROOM"PVCCINFAON_CPU1_CTRL";
"A"14;
%"TAP"
"1","(-6075,4025)","0","mstr_standard","I70";
;
CDS_LIB"mstr_standard"
BODY_TYPE"PLUMBING"
HDL_TAP"TRUE";
"B \NAC \NWC"8;
"S \NAC"
BN"1"115;
%"TAP"
"1","(-6075,4075)","0","mstr_standard","I71";
;
CDS_LIB"mstr_standard"
BODY_TYPE"PLUMBING"
HDL_TAP"TRUE";
"B \NAC \NWC"8;
"S \NAC"
BN"2"116;
%"TAP"
"1","(-6075,3975)","0","mstr_standard","I72";
;
CDS_LIB"mstr_standard"
BODY_TYPE"PLUMBING"
HDL_TAP"TRUE";
"B \NAC \NWC"8;
"S \NAC"
BN"0"114;
%"TAP"
"1","(-7775,4125)","2","mstr_standard","I81";
;
CDS_LIB"mstr_standard"
BODY_TYPE"PLUMBING"
HDL_TAP"TRUE";
"B \NAC \NWC"4;
"S \NAC"
BN"7"171;
%"TAP"
"1","(-7775,4825)","2","mstr_standard","I82";
;
CDS_LIB"mstr_standard"
BODY_TYPE"PLUMBING"
HDL_TAP"TRUE";
"B \NAC \NWC"6;
"S \NAC"
BN"0"167;
%"TAP"
"1","(-7775,4875)","2","mstr_standard","I83";
;
CDS_LIB"mstr_standard"
BODY_TYPE"PLUMBING"
HDL_TAP"TRUE";
"B \NAC \NWC"6;
"S \NAC"
BN"1"166;
%"TAP"
"1","(-7775,4925)","2","mstr_standard","I84";
;
CDS_LIB"mstr_standard"
BODY_TYPE"PLUMBING"
HDL_TAP"TRUE";
"B \NAC \NWC"6;
"S \NAC"
BN"2"164;
%"TAP"
"1","(-7775,4975)","2","mstr_standard","I85";
;
CDS_LIB"mstr_standard"
BODY_TYPE"PLUMBING"
HDL_TAP"TRUE";
"B \NAC \NWC"6;
"S \NAC"
BN"3"162;
%"TAP"
"1","(-7775,5075)","2","mstr_standard","I86";
;
CDS_LIB"mstr_standard"
BODY_TYPE"PLUMBING"
HDL_TAP"TRUE";
"B \NAC \NWC"6;
"S \NAC"
BN"5"159;
%"TAP"
"1","(-7775,5025)","2","mstr_standard","I87";
;
CDS_LIB"mstr_standard"
BODY_TYPE"PLUMBING"
HDL_TAP"TRUE";
"B \NAC \NWC"6;
"S \NAC"
BN"4"161;
%"TAP"
"1","(-7775,5225)","2","mstr_standard","I88";
;
CDS_LIB"mstr_standard"
BODY_TYPE"PLUMBING"
HDL_TAP"TRUE";
"B \NAC \NWC"7;
"S \NAC"
BN"0"34;
%"TAP"
"1","(-7775,5125)","2","mstr_standard","I89";
;
CDS_LIB"mstr_standard"
BODY_TYPE"PLUMBING"
HDL_TAP"TRUE";
"B \NAC \NWC"6;
"S \NAC"
BN"6"157;
%"TAP"
"1","(-7775,5275)","2","mstr_standard","I90";
;
CDS_LIB"mstr_standard"
BODY_TYPE"PLUMBING"
HDL_TAP"TRUE";
"B \NAC \NWC"7;
"S \NAC"
BN"1"77;
%"TAP"
"1","(-7775,5325)","2","mstr_standard","I91";
;
CDS_LIB"mstr_standard"
BODY_TYPE"PLUMBING"
HDL_TAP"TRUE";
"B \NAC \NWC"7;
"S \NAC"
BN"2"165;
%"TAP"
"1","(-7775,5375)","2","mstr_standard","I92";
;
CDS_LIB"mstr_standard"
BODY_TYPE"PLUMBING"
HDL_TAP"TRUE";
"B \NAC \NWC"7;
"S \NAC"
BN"3"163;
%"TAP"
"1","(-7775,5425)","2","mstr_standard","I93";
;
CDS_LIB"mstr_standard"
BODY_TYPE"PLUMBING"
HDL_TAP"TRUE";
"B \NAC \NWC"7;
"S \NAC"
BN"4"78;
%"TAP"
"1","(-7775,5475)","2","mstr_standard","I94";
;
CDS_LIB"mstr_standard"
BODY_TYPE"PLUMBING"
HDL_TAP"TRUE";
"B \NAC \NWC"7;
"S \NAC"
BN"5"160;
%"TAP"
"1","(-7775,5525)","2","mstr_standard","I95";
;
CDS_LIB"mstr_standard"
BODY_TYPE"PLUMBING"
HDL_TAP"TRUE";
"B \NAC \NWC"7;
"S \NAC"
BN"6"158;
%"TAP"
"1","(-6075,4125)","0","mstr_standard","I96";
;
CDS_LIB"mstr_standard"
BODY_TYPE"PLUMBING"
HDL_TAP"TRUE";
"B \NAC \NWC"8;
"S \NAC"
BN"3"117;
%"TAP"
"1","(-6075,4175)","0","mstr_standard","I97";
;
CDS_LIB"mstr_standard"
BODY_TYPE"PLUMBING"
HDL_TAP"TRUE";
"B \NAC \NWC"8;
"S \NAC"
BN"4"118;
%"TAP"
"1","(-6075,4225)","0","mstr_standard","I98";
;
CDS_LIB"mstr_standard"
BODY_TYPE"PLUMBING"
HDL_TAP"TRUE";
"B \NAC \NWC"8;
"S \NAC"
BN"5"119;
%"TAP"
"1","(-6075,4275)","0","mstr_standard","I99";
;
CDS_LIB"mstr_standard"
BODY_TYPE"PLUMBING"
HDL_TAP"TRUE";
"B \NAC \NWC"8;
"S \NAC"
BN"6"120;
END.
